# BASEBOARD_FAB2 (Tioga Pass) — schematic netlist excerpt (pin names and nets, part order shuffled) for the footprints in the layout excerpt that follows; sources: Cadence DE-HDL packaged netlist, KiCad conversion of Wiwynn_Tioga_Pass_MB.brd

U8D7  LCMXO2_A  IC  pkg 256BGA  page 190
  VCC(0)  = P3V3_STBY
  NC(0)  = NC
  PT11C  = FM_PCH_PRSNT_N
  PT10A  = FM_P3V3_CPLD_EN
  PT11A  = TP_CPLD1_PT11A
  PT12D_TDI  = JTAG_PLD_TDI
  PT16C_TCK  = JTAG_PLD_TCK
  PT17B_PCLKC0_1  = TP_CPLD1_PT17B_PCLKC0_1
  PT18C_SCL_PCLKT0_0  = SMB_SENSOR_STBY_LVC3_SCL
  PT19B  = FM_PVCCIN_PVCCSA_CPU0_EN_LVC1
  PT21A  = FM_CPU0_OR_CPU1_MCP_PRES
  PT22B  = PU_THERMTRIP_FORCE_N
  PT24C_INITN  = TP_CPLD1_PT24C_INITN
  PT22D  = TP_CPLD1_PT22D
  PT24B  = TP_CPLD1_PT24B
  VCC(1)  = P3V3_STBY
  PL1C  = RST_PCIE_PCH_PERST_N
  GND(0)  = GND
  PT9C  = FM_CTNR_PS_ON
  PT11D  = PWRGD_PVTT_CPU0
  PT9B  = PWRGD_P12V_MAIN
  PT11B  = TP_CPLD1_PT11B
  PT13A  = TP_CPLD1_PT13A
  PT16D_TMS  = JTAG_PLD_TMS
  PT19A  = PU_RST_PERST_BIT1
  PT20D_PROGRAMN  = PU_CPLD1_PT20D_PROGRAMN
  PT22A  = PWRGD_DSW_PWROK
  PT23B  = FM_PCH_PWRBTN_R1_N
  PT22C  = TP_CPLD1_PT22C
  PT24A  = FM_SINT_PRSNT_N
  GND(1)  = GND
  PR1D  = FM_ADR_COMPLETE_DLY
  PL2C  = RST_PCIE_CPU_DEV1_N
  PL1D  = FM_PCH_PLD_DATA
  GND(2)  = GND
  PT9A  = FM_ADR_SMI_GPIO_R_N
  PT10B  = FM_CPU1_THERMTRIP_LATCH_LVT3_N
  PT12C_TDO  = JTAG_PLD_TDO
  PT13B  = FM_BMC_ONCTL_N
  PT17A_PCLKT0_1  = FM_ADR_COMPLETE
  PT18D_SDA_PCLKC0_0  = SMB_SENSOR_STBY_LVC3_SDA
  PT20C_JTAGENB  = FM_JTAG_PLD_EN_DEBUG
  PT21B  = FM_CPU0_CD_PRES
  PT23A  = FM_SLPS4_N
  PT24D_DONE  = TP_CPLD1_PT24D_DONE
  GND(3)  = GND
  PR1C  = FM_DB1200_PWRGD
  PR2C  = PWRGD_PCH_PWROK
  PL1B_L_GPLLC_FB  = TP_CPLD1_PL1B_L_GPLLC_FB
  PL2D  = FM_MEM_EVENT_FUNC
  PL1A_L_GPLLT_FB  = TP_CPLD1_PL1A_L_GPLLT_FB
  GND(4)  = GND
  VCCIO0(3)  = P3V3_STBY
  PT12A  = RST_PCIE_CPU_DEV0_N
  PT13D  = FM_FORCE_ADR_N
  PT17C  = TP_CPLD1_PT17C
  PT18B  = RST_PCIE_MIDPLANE_N
  PT20A  = TP_CPLD1_PT20A
  PT21D  = FM_CPU0_AND_CPU1_MCP_PRES
  VCCIO0(1)  = P3V3_STBY
  GND(5)  = GND
  PR1A  = PWRGD_SYS_PWROK
  PR2D  = PWRGD_P1V8MCP_CPU0
  PR2A  = PWRGD_P1V8MCP_CPU1
  PL3A_PCLKT5_0  = CLK_32K_SUSCLK_PLD
  PL2A_L_GPLLT_IN  = FM_CPU_CATERR_DLY_LVT3_N
  PL2B_L_GPLLC_IN  = TP_CPLD1_PL2B_L_GPLLC_IN
  VCCIO5(0)  = P3V3_STBY
  GND(6)  = GND
  PT13C  = FM_CPU1_FIVR_FAULT_LVT3_N
  PT12B  = PWRGD_P1V15_BMC_STBY
  PT16B  = TP_CPLD1_PT16B
  PT17D  = FM_SLP_SUS_N
  PT20B  = TP_CPLD1_PT20B
  PT19D  = TP_CPLD1_PT19D
  GND(7)  = GND
  VCCIO1(0)  = P3V3_STBY
  PR2B  = FM_CPLD_ADR_TRIGGER_N
  PR1B  = RST_PLTRST_N
  PR3A  = FM_P1V8MCP_CPU0_EN
  PL4B  = FM_CPU0_PROC_ID0
  PL3B_PCLKC5_0  = FM_CPU0_PKGID0
  PL4A  = FM_CPU0_PROC_ID1
  PL3C  = PU_RST_PERST_BIT0
  PL5C  = FM_CPU0_FIVR_FAULT_LVT3_N
  GND(8)  = GND
  PT16A  = FM_PLD_DEBUG_MODE_N
  PT18A  = SGPIO_BMC_DIN_R
  PT19C  = FM_PS_EN
  PT21C  = FM_CPU1_CD_PRES_N
  GND(9)  = GND
  PR4C  = FM_P1V8MCP_CPU1_EN
  PR3C  = PWRGD_CPUPWRGD
  PR4A  = RST_BMC_SYSRST_BTN_OUT_B_R1_N
  PR3B  = FM_CPU0_MCP_CLK_EN_N
  PR4B  = FM_CPU1_MCP_CLK_EN_N
  PL6A  = FM_SLPS3_N
  PL5A  = FM_CPU0_PKGID2
  PL5B  = FM_CPU0_PKGID1
  PL4D  = RST_RSMRST_R_N
  PL4C  = FM_DEBUG_RST_BTN_N
  PL3D  = FM_PWR_BTN_R2_N
  VCC(4)  = P3V3_STBY
  VCCIO0(0)  = P3V3_STBY
  VCCIO0(2)  = P3V3_STBY
  VCC(5)  = P3V3_STBY
  PR5C  = FM_WBG_PRSNT_N
  PR3D  = FM_CPU0_THERMTRIP_LATCH_LVT3_N
  PR4D  = FM_CPU1_FIVR_FAULT_LVT3
  PR5B  = FM_CPU1_THERMTRIP_LVT3_N
  PR5A  = FM_UV_ADR_TRIGGER_N
  PR6A  = FM_FAST_PROCHOT_THROTTLE_IN_N
  PL7B  = RST_PCIE_CPU_DEV3_N
  PL6B  = FM_PVCCMCP_CPU0_EN
  PL7A  = RST_PCIE_CPU_DEV2_N
  PL6C  = FM_MP_PS_FAIL_N
  PL9C  = NC
  PL5D  = PWRGD_P3V3
  VCCIO4(1)  = P3V3_STBY
  GND(10)  = GND
  GND(11)  = GND
  VCCIO1(1)  = P3V3_STBY
  PR9C  = TP_CPLD1_PR9C
  PR5D  = FM_UV_ADR_TRIGGER_EN
  PR6C  = FM_PVDDQ_GHJ_EN
  PR7A_PCLKT1_0  = TP_CPLD1_PR7A_PCLKT1_0
  PR6B  = FM_PVDDQ_KLM_EN
  PR7B_PCLKC1_0  = TP_CPLD1_PR7B_PCLKC1_0
  PL7C_PCLKT4_0  = SGPIO_BMC_CLK
  PL9A  = SGPIO_BMC_DOUT
  PL7D_PCLKC4_0  = TP_CPLD1_PL7D_PCLKT4_0
  PL9D  = NC
  PL10C  = UART_BMC_RXD5
  PL6D  = PWRGD_P5V
  VCCIO4(0)  = P3V3_STBY
  GND(12)  = GND
  GND(13)  = GND
  VCCIO1(2)  = P3V3_STBY
  PR10C  = TP_CPLD1_PR10C
  PR6D  = FM_FAST_PROCHOT_THROTTLE_DLY_N
  PR9D  = TP_CPLD1_PR9D
  PR7D  = TP_CPLD1_PR7D
  PR9A  = TP_CPLD1_PR9A
  PR7C  = TP_CPLD1_PR7C
  PL9B  = FM_PVCCIOMCP_CPU0_EN
  PL10B  = SP1_BMC_HOST_UART_TX
  PL10A  = SP1_BMC_HOST_UART_RX
  PL11C  = SGPIO_BMC_LD_N
  PL12C  = PWRGD_PVCCIN_CPU0
  PL10D  = UART_BMC_TXD5
  VCC(6)  = P3V3_STBY
  VCCIO2(2)  = P3V3_STBY
  VCCIO2(0)  = P3V3_STBY
  VCC(7)  = P3V3_STBY
  PR12C  = RST_PLTRST_BUF_N
  PR11D  = FM_MEM_THERM_EVENT_PCH_N
  PR11C  = FM_MEM_THERM_EVENT_LVT3_N
  PR10A  = FM_PVDDQ_ABC_EN
  PR10B  = FM_PVDDQ_DEF_EN
  PR9B  = PU_FAB2_MARKER_CPLD
  PL11A  = PWRGD_PVSA_CPU0
  PL12A_PCLKT3_0  = CLK_25M_CPLD
  PL11B  = TP_CPLD1_PL11A
  PL12D  = PWRGD_PVCCMCP_CPU1
  PL11D  = PWRGD_CPU0_LVC3
  GND(14)  = GND
  PB8D  = FM_OC0_USB_N
  PB11D  = PWRGD_PVCCIO_CPU0
  PB12D  = FM_IE_DISABLE_N
  PB18D  = FM_SOL_UART_CH_SEL
  GND(15)  = GND
  PR10D  = PWRGD_P3V3_STBY
  PR12D  = TP_CPLD1_PR12D
  PR11B  = TP_CPLD1_PR11B
  PR12A  = FM_THERMTRIP_DLY
  PR11A  = PWRGD_PVCCIO_CPU1
  PL12B_PCLKC3_0  = RST_RSMRST_DLY
  PL14A  = PWRGD_PVPP_GHJ
  PL13A  = RST_PCIE_RISER1_PERST_N
  VCCIO3(0)  = P3V3_STBY
  GND(16)  = GND
  PB11C  = PWRGD_PVPP_DEF
  PB9C  = FM_PVCCIO_CPU0_EN
  PB16C  = FM_PVCCMCP_CPU1_EN
  PB18C  = FM_CPLD_UART_CH_LOCK_N
  PB21C  = PWRGD_CPU1_LVC3
  PB19D  = XDP_PWRGD_RST_N
  GND(17)  = GND
  VCCIO1(3)  = P3V3_STBY
  PR13A  = FM_CPU1_PROC_ID1
  PR13B  = FM_CPU1_PROC_ID0
  PR12B  = FM_CPU0_FIVR_FAULT_LVT3
  PL13B  = PWRGD_PVCCIN_CPU1
  PL13C  = PWRGD_PVPP_KLM
  PL14B  = RST_CD_CPU0_POR_N
  GND(18)  = GND
  VCCIO2(3)  = P3V3_STBY
  PB8C  = PWRGD_PVCCIOMCP_CPU0
  PB9D  = PWRGD_PVPP_ABC
  PB12C  = FM_156M_CPU1_BRD_OSC_EN
  PB16D  = FM_CPLD_BMC_PWRDN_N
  PB19C  = RST_CPU1_LVC3_R1_N
  PB21D  = XDP_SYSPWROK
  VCCIO2(1)  = P3V3_STBY
  GND(19)  = GND
  PR14B  = FM_CPU1_VRM_OSC_EN
  PR13C  = FM_CPU0_THERMTRIP_LVT3_N
  PR14A  = FM_PVCCIN_PVCCSA_CPU1_EN_LVC1
  PL13D  = FM_GLOBAL_RST_WARN_N
  PL14D  = FM_UART_ALERT_N
  GND(20)  = GND
  PB3A  = FM_CPU1_RC_EN
  PB5B  = PWRGD_PVCCMCP_CPU0
  PB8A_MCLK_CCLK  = TP_CPLD1_PB8A_MCLK_CCLK
  PB9B  = FM_PVCCIOMCP_CPU1_EN
  PB12A  = PWRGD_PVNN_P1V05_PCH
  PB16B_PCLKC2_1  = TP_CPLD1_PB16B_PCLKC2_1
  PB19A  = RST_CD_CPU1_POR_N
  PB21B  = FM_UARTSW_MSB_N
  PB24A  = FM_CPU1_PKGID1
  PB25B_SI_SISPI  = TP_CPLD1_PB25B_SI_SISPI
  GND(21)  = GND
  PR14C  = FM_PVPP_CPU0_EN
  PR13D  = FM_PVPP_CPU1_EN
  PL14C  = FM_BMC_CPLD_GPO
  GND(22)  = GND
  PB3D  = FM_CPU0_RC_EN
  PB6D  = FM_BMC_CPLD_MP_RST_N
  PB5A_CSSPIN  = TP_CPLD1_PB5A_CSSPIN
  PB6B  = RST_PCIE_M2_DEV_N
  PB9A  = PWRGD_PVTT_CPU1
  PB11B_PCLKC2_0  = FM_CPLD_USB_P0_EN_N
  PB18A  = FM_UARTSW_LSB_N
  PB19B  = RST_CPU0_LVC3_R1_N
  PB22A  = FM_DB1200ZL_BCLKS_EN_N
  PB25A_SN  = FM_CPU1_PKGID0
  PB22C  = FM_CPU0_VRM_OSC_EN
  PB25D  = FM_CPU_CATERR_LVT3_N
  GND(23)  = GND
  PR14D  = FM_P12V_MAIN_SW_EN
  VCC(2)  = P3V3_STBY
  PB3C  = FM_ADR_MODE_SEL
  PB6C  = FM_DIS_ADR_DLY
  PB3B  = PWRGD_PVSA_CPU1
  PB6A  = PWRGD_PVCCIOMCP_CPU1
  PB8B_SO_SPISO  = TP_CPLD1_PB8B_SO_SPISO
  PB11A_PCLKT2_0  = FM_PVCCIO_CPU1_EN
  PB12B  = FM_CPLD_DBG_PWR_EN_N
  PB16A_PCLKT2_1  = TP_CPLD1_PB16A_PCLKT2_1
  PB18B  = FM_156M_CPU0_BRD_OSC_EN
  PB21A  = FM_CPU1_PKGID2
  PB22B  = FM_CPU1_SKTOCC_LVT3_N
  PB24B  = FM_CPU_MSMI_LVT3_N
  PB22D  = FM_CPU0_SKTOCC_LVT3_N
  PB25C  = PWRGD_DRAMPWRGD
  VCC(3)  = P3V3_STBY

(kicad_pcb
	(version 20260206)
	(generator "pcbnew")
	(generator_version "10.0")
	(general
		(thickness 1.6)
		(legacy_teardrops no)
	)
	(paper "A4")
	(title_block
		(title "Wiwynn_Tioga_Pass_MB.brd")
		(comment 1 "Tioga Pass / footprint 2035 of 4770 (U8D7), pads 45-89 of 256")
	)
	(layers
		(0 "F.Cu" signal "TOP")
		(4 "In1.Cu" signal "L2GND")
		(6 "In2.Cu" signal "L3")
		(8 "In3.Cu" signal "L4GND")
		(10 "In4.Cu" signal "L5")
		(12 "In5.Cu" signal "L6GND")
		(14 "In6.Cu" signal "L7VCC")
		(16 "In7.Cu" signal "L8VCC")
		(18 "In8.Cu" signal "L9GND")
		(20 "In9.Cu" signal "L10")
		(22 "In10.Cu" signal "L11GND")
		(24 "In11.Cu" signal "L12")
		(26 "In12.Cu" signal "L13GND")
		(2 "B.Cu" signal "BOTTOM")
		(9 "F.Adhes" user "F.Adhesive")
		(11 "B.Adhes" user "B.Adhesive")
		(13 "F.Paste" user "Package Geometry/Pastemask Top")
		(15 "B.Paste" user "Package Geometry/Pastemask Bottom")
		(5 "F.SilkS" user "Ref Des/Silkscreen Top")
		(7 "B.SilkS" user "Ref Des/Silkscreen Bottom")
		(1 "F.Mask" user "Board Geometry/Soldermask Top")
		(3 "B.Mask" user "Board Geometry/Soldermask Bottom")
		(17 "Dwgs.User" user "User.Drawings")
		(19 "Cmts.User" user "User.Comments")
		(21 "Eco1.User" user "User.Eco1")
		(23 "Eco2.User" user "User.Eco2")
		(25 "Edge.Cuts" user "Board Geometry/Outline")
		(27 "Margin" user)
		(31 "F.CrtYd" user "Package Geometry/Place Bound Top")
		(29 "B.CrtYd" user "Package Geometry/Place Bound Bottom")
		(35 "F.Fab" user "Ref Des/Assembly Top")
		(33 "B.Fab" user "Ref Des/Assembly Bottom")
	)
	(footprint ""
		(layer "F.Cu")
		(at 372.745 -74.295 180)
		(property "Reference" "U8D7"
			(at -0.635 -8.28167 0)
			(unlocked yes)
			(layer "F.SilkS")
			(effects
				(font
					(size 0.7874 0.5842)
					(thickness 0.1524)
				)
			)
		)
		(property "Value" ""
			(at 0 0 180)
			(layer "F.Fab")
			(effects
				(font
					(size 1.27 1.27)
				)
			)
		)
		(duplicate_pad_numbers_are_jumpers no)
		(pad "C13" smd circle
			(at 3.599942 -4.400042 180)
			(size 0.3556 0.3556)
			(layers "F.Cu" "F.Mask" "F.Paste")
			(net "TP_CPLD1_PT24D_DONE")
		)
		(pad "C14" smd circle
			(at 4.400042 -4.400042 180)
			(size 0.3556 0.3556)
			(layers "F.Cu" "F.Mask" "F.Paste")
			(net "GND")
		)
		(pad "C15" smd circle
			(at 5.199888 -4.400042 180)
			(size 0.3556 0.3556)
			(layers "F.Cu" "F.Mask" "F.Paste")
			(net "FM_DB1200_PWRGD")
		)
		(pad "C16" smd circle
			(at 5.999988 -4.400042 180)
			(size 0.3556 0.3556)
			(layers "F.Cu" "F.Mask" "F.Paste")
			(net "PWRGD_PCH_PWROK")
		)
		(pad "D1" smd circle
			(at -5.999988 -3.599942 180)
			(size 0.3556 0.3556)
			(layers "F.Cu" "F.Mask" "F.Paste")
			(net "TP_CPLD1_PL1B_L_GPLLC_FB")
		)
		(pad "D2" smd circle
			(at -5.199888 -3.599942 180)
			(size 0.3556 0.3556)
			(layers "F.Cu" "F.Mask" "F.Paste")
			(net "FM_MEM_EVENT_FUNC")
		)
		(pad "D3" smd circle
			(at -4.400042 -3.599942 180)
			(size 0.3556 0.3556)
			(layers "F.Cu" "F.Mask" "F.Paste")
			(net "TP_CPLD1_PL1A_L_GPLLT_FB")
		)
		(pad "D4" smd circle
			(at -3.599942 -3.599942 180)
			(size 0.3556 0.3556)
			(layers "F.Cu" "F.Mask" "F.Paste")
			(net "GND")
		)
		(pad "D5" smd circle
			(at -2.800096 -3.599942 180)
			(size 0.3556 0.3556)
			(layers "F.Cu" "F.Mask" "F.Paste")
			(net "P3V3_STBY")
		)
		(pad "D6" smd circle
			(at -1.999996 -3.599942 180)
			(size 0.3556 0.3556)
			(layers "F.Cu" "F.Mask" "F.Paste")
			(net "RST_PCIE_CPU_DEV0_N")
		)
		(pad "D7" smd circle
			(at -1.199896 -3.599942 180)
			(size 0.3556 0.3556)
			(layers "F.Cu" "F.Mask" "F.Paste")
			(net "FM_FORCE_ADR_N")
		)
		(pad "D8" smd circle
			(at -0.40005 -3.599942 180)
			(size 0.3556 0.3556)
			(layers "F.Cu" "F.Mask" "F.Paste")
			(net "TP_CPLD1_PT17C")
		)
		(pad "D9" smd circle
			(at 0.40005 -3.599942 180)
			(size 0.3556 0.3556)
			(layers "F.Cu" "F.Mask" "F.Paste")
			(net "RST_PCIE_MIDPLANE_N")
		)
		(pad "D10" smd circle
			(at 1.199896 -3.599942 180)
			(size 0.3556 0.3556)
			(layers "F.Cu" "F.Mask" "F.Paste")
			(net "TP_CPLD1_PT20A")
		)
		(pad "D11" smd circle
			(at 1.999996 -3.599942 180)
			(size 0.3556 0.3556)
			(layers "F.Cu" "F.Mask" "F.Paste")
			(net "FM_CPU0_AND_CPU1_MCP_PRES")
		)
		(pad "D12" smd circle
			(at 2.800096 -3.599942 180)
			(size 0.3556 0.3556)
			(layers "F.Cu" "F.Mask" "F.Paste")
			(net "P3V3_STBY")
		)
		(pad "D13" smd circle
			(at 3.599942 -3.599942 180)
			(size 0.3556 0.3556)
			(layers "F.Cu" "F.Mask" "F.Paste")
			(net "GND")
		)
		(pad "D14" smd circle
			(at 4.400042 -3.599942 180)
			(size 0.3556 0.3556)
			(layers "F.Cu" "F.Mask" "F.Paste")
			(net "PWRGD_SYS_PWROK")
		)
		(pad "D15" smd circle
			(at 5.199888 -3.599942 180)
			(size 0.3556 0.3556)
			(layers "F.Cu" "F.Mask" "F.Paste")
			(net "PWRGD_P1V8MCP_CPU0")
		)
		(pad "D16" smd circle
			(at 5.999988 -3.599942 180)
			(size 0.3556 0.3556)
			(layers "F.Cu" "F.Mask" "F.Paste")
			(net "PWRGD_P1V8MCP_CPU1")
		)
		(pad "E1" smd circle
			(at -5.999988 -2.800096 180)
			(size 0.3556 0.3556)
			(layers "F.Cu" "F.Mask" "F.Paste")
			(net "CLK_32K_SUSCLK_PLD")
		)
		(pad "E2" smd circle
			(at -5.199888 -2.800096 180)
			(size 0.3556 0.3556)
			(layers "F.Cu" "F.Mask" "F.Paste")
			(net "FM_CPU_CATERR_DLY_LVT3_N")
		)
		(pad "E3" smd circle
			(at -4.400042 -2.800096 180)
			(size 0.3556 0.3556)
			(layers "F.Cu" "F.Mask" "F.Paste")
			(net "TP_CPLD1_PL2B_L_GPLLC_IN")
		)
		(pad "E4" smd circle
			(at -3.599942 -2.800096 180)
			(size 0.3556 0.3556)
			(layers "F.Cu" "F.Mask" "F.Paste")
			(net "P3V3_STBY")
		)
		(pad "E5" smd circle
			(at -2.800096 -2.800096 180)
			(size 0.3556 0.3556)
			(layers "F.Cu" "F.Mask" "F.Paste")
			(net "GND")
		)
		(pad "E6" smd circle
			(at -1.999996 -2.800096 180)
			(size 0.3556 0.3556)
			(layers "F.Cu" "F.Mask" "F.Paste")
			(net "FM_CPU1_FIVR_FAULT_LVT3_N")
		)
		(pad "E7" smd circle
			(at -1.199896 -2.800096 180)
			(size 0.3556 0.3556)
			(layers "F.Cu" "F.Mask" "F.Paste")
			(net "PWRGD_P1V15_BMC_STBY")
		)
		(pad "E8" smd circle
			(at -0.40005 -2.800096 180)
			(size 0.3556 0.3556)
			(layers "F.Cu" "F.Mask" "F.Paste")
			(net "TP_CPLD1_PT16B")
		)
		(pad "E9" smd circle
			(at 0.40005 -2.800096 180)
			(size 0.3556 0.3556)
			(layers "F.Cu" "F.Mask" "F.Paste")
			(net "FM_SLP_SUS_N")
		)
		(pad "E10" smd circle
			(at 1.199896 -2.800096 180)
			(size 0.3556 0.3556)
			(layers "F.Cu" "F.Mask" "F.Paste")
			(net "TP_CPLD1_PT20B")
		)
		(pad "E11" smd circle
			(at 1.999996 -2.800096 180)
			(size 0.3556 0.3556)
			(layers "F.Cu" "F.Mask" "F.Paste")
			(net "TP_CPLD1_PT19D")
		)
		(pad "E12" smd circle
			(at 2.800096 -2.800096 180)
			(size 0.3556 0.3556)
			(layers "F.Cu" "F.Mask" "F.Paste")
			(net "GND")
		)
		(pad "E13" smd circle
			(at 3.599942 -2.800096 180)
			(size 0.3556 0.3556)
			(layers "F.Cu" "F.Mask" "F.Paste")
			(net "P3V3_STBY")
		)
		(pad "E14" smd circle
			(at 4.400042 -2.800096 180)
			(size 0.3556 0.3556)
			(layers "F.Cu" "F.Mask" "F.Paste")
			(net "FM_CPLD_ADR_TRIGGER_N")
		)
		(pad "E15" smd circle
			(at 5.199888 -2.800096 180)
			(size 0.3556 0.3556)
			(layers "F.Cu" "F.Mask" "F.Paste")
			(net "RST_PLTRST_N")
		)
		(pad "E16" smd circle
			(at 5.999988 -2.800096 180)
			(size 0.3556 0.3556)
			(layers "F.Cu" "F.Mask" "F.Paste")
			(net "FM_P1V8MCP_CPU0_EN")
		)
		(pad "F1" smd circle
			(at -5.999988 -1.999996 180)
			(size 0.3556 0.3556)
			(layers "F.Cu" "F.Mask" "F.Paste")
			(net "FM_CPU0_PROC_ID0")
		)
		(pad "F2" smd circle
			(at -5.199888 -1.999996 180)
			(size 0.3556 0.3556)
			(layers "F.Cu" "F.Mask" "F.Paste")
			(net "FM_CPU0_PKGID0")
		)
		(pad "F3" smd circle
			(at -4.400042 -1.999996 180)
			(size 0.3556 0.3556)
			(layers "F.Cu" "F.Mask" "F.Paste")
			(net "FM_CPU0_PROC_ID1")
		)
		(pad "F4" smd circle
			(at -3.599942 -1.999996 180)
			(size 0.3556 0.3556)
			(layers "F.Cu" "F.Mask" "F.Paste")
			(net "PU_RST_PERST_BIT0")
		)
		(pad "F5" smd circle
			(at -2.800096 -1.999996 180)
			(size 0.3556 0.3556)
			(layers "F.Cu" "F.Mask" "F.Paste")
			(net "FM_CPU0_FIVR_FAULT_LVT3_N")
		)
		(pad "F6" smd circle
			(at -1.999996 -1.999996 180)
			(size 0.3556 0.3556)
			(layers "F.Cu" "F.Mask" "F.Paste")
			(net "GND")
		)
		(pad "F7" smd circle
			(at -1.199896 -1.999996 180)
			(size 0.3556 0.3556)
			(layers "F.Cu" "F.Mask" "F.Paste")
			(net "FM_PLD_DEBUG_MODE_N")
		)
		(pad "F8" smd circle
			(at -0.40005 -1.999996 180)
			(size 0.3556 0.3556)
			(layers "F.Cu" "F.Mask" "F.Paste")
			(net "SGPIO_BMC_DIN_R")
		)
		(pad "F9" smd circle
			(at 0.40005 -1.999996 180)
			(size 0.3556 0.3556)
			(layers "F.Cu" "F.Mask" "F.Paste")
			(net "FM_PS_EN")
		)
	)
)
